(kicad_pcb
	(version 20260206)
	(generator "pcbnew")
	(generator_version "10.0")
	(general
		(thickness 1.6)
		(legacy_teardrops no)
	)
	(paper "A4")
	(title_block
		(title "Bryce Canyon_IOM_M2_16342-2_OCP.brd")
		(comment 1 "Bryce Canyon / footprints 1066-1073 of 1146")
	)
	(layers
		(0 "F.Cu" signal "TOP")
		(4 "In1.Cu" signal "L2GND")
		(6 "In2.Cu" signal "L3")
		(8 "In3.Cu" signal "L4VCC")
		(10 "In4.Cu" signal "L5VCC")
		(12 "In5.Cu" signal "L6")
		(14 "In6.Cu" signal "L7GND")
		(2 "B.Cu" signal "BOTTOM")
		(9 "F.Adhes" user "F.Adhesive")
		(11 "B.Adhes" user "B.Adhesive")
		(13 "F.Paste" user "Package Geometry/Pastemask Top")
		(15 "B.Paste" user "Package Geometry/Pastemask Bottom")
		(5 "F.SilkS" user "Ref Des/Silkscreen Top")
		(7 "B.SilkS" user "Ref Des/Silkscreen Bottom")
		(1 "F.Mask" user "Board Geometry/Soldermask Top")
		(3 "B.Mask" user "Board Geometry/Soldermask Bottom")
		(17 "Dwgs.User" user "User.Drawings")
		(19 "Cmts.User" user "User.Comments")
		(21 "Eco1.User" user "User.Eco1")
		(23 "Eco2.User" user "User.Eco2")
		(25 "Edge.Cuts" user "Board Geometry/Outline")
		(27 "Margin" user)
		(31 "F.CrtYd" user "Package Geometry/Place Bound Top")
		(29 "B.CrtYd" user "Package Geometry/Place Bound Bottom")
		(35 "F.Fab" user "Ref Des/Assembly Top")
		(33 "B.Fab" user "Ref Des/Assembly Bottom")
	)
	(footprint ""
		(layer "B.Cu")
		(at 10.200132 -138.145774 90)
		(property "Reference" "R246"
			(at 0 0 90)
			(layer "B.SilkS")
			(hide yes)
			(effects
				(font
					(size 1.27 1.27)
				)
				(justify mirror)
			)
		)
		(property "Value" "120R2F-GP"
			(at -0.064008 -3.993896 90)
			(unlocked yes)
			(layer "B.Fab")
			(hide yes)
			(effects
				(font
					(size 1.016 1.016)
					(thickness 0.1524)
				)
				(justify mirror)
			)
		)
		(property "Device Type" "R402H16"
			(at -0.064008 -5.517896 90)
			(unlocked yes)
			(layer "B.Fab")
			(hide yes)
			(effects
				(font
					(size 1.016 1.016)
					(thickness 0.1524)
				)
				(justify mirror)
			)
		)
		(duplicate_pad_numbers_are_jumpers no)
		(fp_line
			(start 0.508 -0.9398)
			(end 0.508 0.9398)
			(stroke
				(width 0.1524)
				(type default)
			)
			(layer "B.SilkS")
		)
		(fp_line
			(start -0.508 -0.9398)
			(end 0.508 -0.9398)
			(stroke
				(width 0.1524)
				(type default)
			)
			(layer "B.SilkS")
		)
		(fp_rect
			(start 0.508 0.9398)
			(end -0.508 -0.9398)
			(stroke
				(width 0)
				(type default)
			)
			(fill no)
			(layer "B.CrtYd")
		)
		(fp_rect
			(start 0.508 0.9398)
			(end -0.508 -0.9398)
			(stroke
				(width 0)
				(type default)
			)
			(fill no)
			(layer "B.Fab")
		)
		(pad "1" smd custom
			(at 0 -0.4445 270)
			(size 0.1397 0.1397)
			(layers "B.Cu" "B.Mask" "B.Paste")
			(net "GND")
			(options
				(clearance outline)
				(anchor circle)
			)
			(primitives
				(gr_poly
					(pts
						(arc
							(start -0.1778 0.2794)
							(mid -0.249642 0.249642)
							(end -0.2794 0.1778)
						)
						(arc
							(start -0.2794 -0.1778)
							(mid -0.249642 -0.249642)
							(end -0.1778 -0.2794)
						)
						(arc
							(start 0.1778 -0.2794)
							(mid 0.249642 -0.249642)
							(end 0.2794 -0.1778)
						)
						(arc
							(start 0.2794 0.1778)
							(mid 0.249642 0.249642)
							(end 0.1778 0.2794)
						)
					)
					(width 0)
					(fill yes)
				)
			)
		)
		(pad "2" smd custom
			(at 0 0.4445 270)
			(size 0.1397 0.1397)
			(layers "B.Cu" "B.Mask" "B.Paste")
			(net "MEMA_6")
			(options
				(clearance outline)
				(anchor circle)
			)
			(primitives
				(gr_poly
					(pts
						(arc
							(start -0.1778 0.2794)
							(mid -0.249642 0.249642)
							(end -0.2794 0.1778)
						)
						(arc
							(start -0.2794 -0.1778)
							(mid -0.249642 -0.249642)
							(end -0.1778 -0.2794)
						)
						(arc
							(start 0.1778 -0.2794)
							(mid 0.249642 -0.249642)
							(end 0.2794 -0.1778)
						)
						(arc
							(start 0.2794 0.1778)
							(mid 0.249642 0.249642)
							(end 0.1778 0.2794)
						)
					)
					(width 0)
					(fill yes)
				)
			)
		)
	)
	(footprint ""
		(layer "B.Cu")
		(at 56.3372 -154.94)
		(property "Reference" "R304"
			(at 0 0 0)
			(layer "B.SilkS")
			(hide yes)
			(effects
				(font
					(size 1.27 1.27)
				)
				(justify mirror)
			)
		)
		(property "Value" "47KR2F-GP"
			(at -0.064008 -3.993896 0)
			(unlocked yes)
			(layer "B.Fab")
			(hide yes)
			(effects
				(font
					(size 1.016 1.016)
					(thickness 0.1524)
				)
				(justify mirror)
			)
		)
		(property "Device Type" "R402H16"
			(at -0.064008 -5.517896 0)
			(unlocked yes)
			(layer "B.Fab")
			(hide yes)
			(effects
				(font
					(size 1.016 1.016)
					(thickness 0.1524)
				)
				(justify mirror)
			)
		)
		(duplicate_pad_numbers_are_jumpers no)
		(fp_line
			(start -0.508 -0.9398)
			(end 0.508 -0.9398)
			(stroke
				(width 0.1524)
				(type default)
			)
			(layer "B.SilkS")
		)
		(fp_line
			(start 0.508 -0.9398)
			(end 0.508 0.9398)
			(stroke
				(width 0.1524)
				(type default)
			)
			(layer "B.SilkS")
		)
		(fp_rect
			(start 0.508 0.9398)
			(end -0.508 -0.9398)
			(stroke
				(width 0)
				(type default)
			)
			(fill no)
			(layer "B.CrtYd")
		)
		(fp_rect
			(start 0.508 0.9398)
			(end -0.508 -0.9398)
			(stroke
				(width 0)
				(type default)
			)
			(fill no)
			(layer "B.Fab")
		)
		(pad "1" smd custom
			(at 0 -0.4445 180)
			(size 0.1397 0.1397)
			(layers "B.Cu" "B.Mask" "B.Paste")
			(net "GND")
			(options
				(clearance outline)
				(anchor circle)
			)
			(primitives
				(gr_poly
					(pts
						(arc
							(start -0.1778 0.2794)
							(mid -0.249642 0.249642)
							(end -0.2794 0.1778)
						)
						(arc
							(start -0.2794 -0.1778)
							(mid -0.249642 -0.249642)
							(end -0.1778 -0.2794)
						)
						(arc
							(start 0.1778 -0.2794)
							(mid 0.249642 -0.249642)
							(end 0.2794 -0.1778)
						)
						(arc
							(start 0.2794 0.1778)
							(mid 0.249642 0.249642)
							(end 0.1778 0.2794)
						)
					)
					(width 0)
					(fill yes)
				)
			)
		)
		(pad "2" smd custom
			(at 0 0.4445 180)
			(size 0.1397 0.1397)
			(layers "B.Cu" "B.Mask" "B.Paste")
			(net "BMC_RGMII_A4_D3")
			(options
				(clearance outline)
				(anchor circle)
			)
			(primitives
				(gr_poly
					(pts
						(arc
							(start -0.1778 0.2794)
							(mid -0.249642 0.249642)
							(end -0.2794 0.1778)
						)
						(arc
							(start -0.2794 -0.1778)
							(mid -0.249642 -0.249642)
							(end -0.1778 -0.2794)
						)
						(arc
							(start 0.1778 -0.2794)
							(mid 0.249642 -0.249642)
							(end 0.2794 -0.1778)
						)
						(arc
							(start 0.2794 0.1778)
							(mid 0.249642 0.249642)
							(end 0.1778 0.2794)
						)
					)
					(width 0)
					(fill yes)
				)
			)
		)
	)
	(footprint ""
		(layer "B.Cu")
		(at 17.749012 -129.051558 180)
		(property "Reference" "R240"
			(at 0 0 0)
			(layer "B.SilkS")
			(hide yes)
			(effects
				(font
					(size 1.27 1.27)
				)
				(justify mirror)
			)
		)
		(property "Value" "120R2F-GP"
			(at -0.064008 -3.993896 180)
			(unlocked yes)
			(layer "B.Fab")
			(hide yes)
			(effects
				(font
					(size 1.016 1.016)
					(thickness 0.1524)
				)
				(justify mirror)
			)
		)
		(property "Device Type" "R402H16"
			(at -0.064008 -5.517896 180)
			(unlocked yes)
			(layer "B.Fab")
			(hide yes)
			(effects
				(font
					(size 1.016 1.016)
					(thickness 0.1524)
				)
				(justify mirror)
			)
		)
		(duplicate_pad_numbers_are_jumpers no)
		(fp_line
			(start 0.508 -0.9398)
			(end 0.508 0.9398)
			(stroke
				(width 0.1524)
				(type default)
			)
			(layer "B.SilkS")
		)
		(fp_line
			(start -0.508 -0.9398)
			(end 0.508 -0.9398)
			(stroke
				(width 0.1524)
				(type default)
			)
			(layer "B.SilkS")
		)
		(fp_rect
			(start 0.508 0.9398)
			(end -0.508 -0.9398)
			(stroke
				(width 0)
				(type default)
			)
			(fill no)
			(layer "B.CrtYd")
		)
		(fp_rect
			(start 0.508 0.9398)
			(end -0.508 -0.9398)
			(stroke
				(width 0)
				(type default)
			)
			(fill no)
			(layer "B.Fab")
		)
		(pad "1" smd custom
			(at 0 -0.4445)
			(size 0.1397 0.1397)
			(layers "B.Cu" "B.Mask" "B.Paste")
			(net "GND")
			(options
				(clearance outline)
				(anchor circle)
			)
			(primitives
				(gr_poly
					(pts
						(arc
							(start -0.1778 0.2794)
							(mid -0.249642 0.249642)
							(end -0.2794 0.1778)
						)
						(arc
							(start -0.2794 -0.1778)
							(mid -0.249642 -0.249642)
							(end -0.1778 -0.2794)
						)
						(arc
							(start 0.1778 -0.2794)
							(mid 0.249642 -0.249642)
							(end 0.2794 -0.1778)
						)
						(arc
							(start 0.2794 0.1778)
							(mid 0.249642 0.249642)
							(end 0.1778 0.2794)
						)
					)
					(width 0)
					(fill yes)
				)
			)
		)
		(pad "2" smd custom
			(at 0 0.4445)
			(size 0.1397 0.1397)
			(layers "B.Cu" "B.Mask" "B.Paste")
			(net "MEMA_3")
			(options
				(clearance outline)
				(anchor circle)
			)
			(primitives
				(gr_poly
					(pts
						(arc
							(start -0.1778 0.2794)
							(mid -0.249642 0.249642)
							(end -0.2794 0.1778)
						)
						(arc
							(start -0.2794 -0.1778)
							(mid -0.249642 -0.249642)
							(end -0.1778 -0.2794)
						)
						(arc
							(start 0.1778 -0.2794)
							(mid 0.249642 -0.249642)
							(end 0.2794 -0.1778)
						)
						(arc
							(start 0.2794 0.1778)
							(mid 0.249642 0.249642)
							(end 0.1778 0.2794)
						)
					)
					(width 0)
					(fill yes)
				)
			)
		)
	)
	(footprint ""
		(layer "B.Cu")
		(at 32.5374 -160.2232 90)
		(property "Reference" "R705"
			(at 0 0 90)
			(layer "B.SilkS")
			(hide yes)
			(effects
				(font
					(size 1.27 1.27)
				)
				(justify mirror)
			)
		)
		(property "Value" "4K7R2F-GP"
			(at -0.064008 -3.993896 90)
			(unlocked yes)
			(layer "B.Fab")
			(hide yes)
			(effects
				(font
					(size 1.016 1.016)
					(thickness 0.1524)
				)
				(justify mirror)
			)
		)
		(property "Device Type" "R402H16"
			(at -0.064008 -5.517896 90)
			(unlocked yes)
			(layer "B.Fab")
			(hide yes)
			(effects
				(font
					(size 1.016 1.016)
					(thickness 0.1524)
				)
				(justify mirror)
			)
		)
		(duplicate_pad_numbers_are_jumpers no)
		(fp_line
			(start 0.508 -0.9398)
			(end 0.508 0.9398)
			(stroke
				(width 0.1524)
				(type default)
			)
			(layer "B.SilkS")
		)
		(fp_line
			(start -0.508 -0.9398)
			(end 0.508 -0.9398)
			(stroke
				(width 0.1524)
				(type default)
			)
			(layer "B.SilkS")
		)
		(fp_rect
			(start 0.508 0.9398)
			(end -0.508 -0.9398)
			(stroke
				(width 0)
				(type default)
			)
			(fill no)
			(layer "B.CrtYd")
		)
		(fp_rect
			(start 0.508 0.9398)
			(end -0.508 -0.9398)
			(stroke
				(width 0)
				(type default)
			)
			(fill no)
			(layer "B.Fab")
		)
		(pad "1" smd custom
			(at 0 -0.4445 270)
			(size 0.1397 0.1397)
			(layers "B.Cu" "B.Mask" "B.Paste")
			(net "P3V3_STBY")
			(options
				(clearance outline)
				(anchor circle)
			)
			(primitives
				(gr_poly
					(pts
						(arc
							(start -0.1778 0.2794)
							(mid -0.249642 0.249642)
							(end -0.2794 0.1778)
						)
						(arc
							(start -0.2794 -0.1778)
							(mid -0.249642 -0.249642)
							(end -0.1778 -0.2794)
						)
						(arc
							(start 0.1778 -0.2794)
							(mid 0.249642 -0.249642)
							(end 0.2794 -0.1778)
						)
						(arc
							(start 0.2794 0.1778)
							(mid 0.249642 0.249642)
							(end 0.1778 0.2794)
						)
					)
					(width 0)
					(fill yes)
				)
			)
		)
		(pad "2" smd custom
			(at 0 0.4445 270)
			(size 0.1397 0.1397)
			(layers "B.Cu" "B.Mask" "B.Paste")
			(net "IOM_TYPE2")
			(options
				(clearance outline)
				(anchor circle)
			)
			(primitives
				(gr_poly
					(pts
						(arc
							(start -0.1778 0.2794)
							(mid -0.249642 0.249642)
							(end -0.2794 0.1778)
						)
						(arc
							(start -0.2794 -0.1778)
							(mid -0.249642 -0.249642)
							(end -0.1778 -0.2794)
						)
						(arc
							(start 0.1778 -0.2794)
							(mid 0.249642 -0.249642)
							(end 0.2794 -0.1778)
						)
						(arc
							(start 0.2794 0.1778)
							(mid 0.249642 0.249642)
							(end 0.1778 0.2794)
						)
					)
					(width 0)
					(fill yes)
				)
			)
		)
	)
	(footprint ""
		(layer "B.Cu")
		(at 39.345362 -154.548332)
		(property "Reference" "TP64"
			(at 0 0 0)
			(layer "B.SilkS")
			(hide yes)
			(effects
				(font
					(size 1.27 1.27)
				)
				(justify mirror)
			)
		)
		(property "Value" "TPAD28-2-GP"
			(at 0.0127 -1.6637 0)
			(unlocked yes)
			(layer "B.Fab")
			(hide yes)
			(effects
				(font
					(size 1.016 1.016)
					(thickness 0.1524)
				)
				(justify mirror)
			)
		)
		(property "Device Type" "TPAD28"
			(at 0.0127 -3.1877 0)
			(unlocked yes)
			(layer "B.Fab")
			(hide yes)
			(effects
				(font
					(size 1.016 1.016)
					(thickness 0.1524)
				)
				(justify mirror)
			)
		)
		(duplicate_pad_numbers_are_jumpers no)
		(fp_poly
			(pts
				(arc
					(start 0.3556 0)
					(mid -0.3556 0)
					(end 0.3556 0)
				)
			)
			(stroke
				(width 0)
				(type default)
			)
			(fill no)
			(layer "B.CrtYd")
		)
		(fp_poly
			(pts
				(arc
					(start 0.6096 0)
					(mid -0.6096 0)
					(end 0.6096 0)
				)
			)
			(stroke
				(width 0)
				(type default)
			)
			(fill no)
			(layer "B.Fab")
		)
		(pad "1" smd circle
			(at 0 0 180)
			(size 0.7112 0.7112)
			(layers "B.Cu" "B.Mask" "B.Paste")
			(net "TP_BMC_GPION4")
		)
	)
	(footprint ""
		(layer "B.Cu")
		(at 45.593 -153.1112)
		(property "Reference" "TP191"
			(at 0 0 0)
			(layer "B.SilkS")
			(hide yes)
			(effects
				(font
					(size 1.27 1.27)
				)
				(justify mirror)
			)
		)
		(property "Value" "TPAD28-2-GP"
			(at 0.0127 -1.6637 0)
			(unlocked yes)
			(layer "B.Fab")
			(hide yes)
			(effects
				(font
					(size 1.016 1.016)
					(thickness 0.1524)
				)
				(justify mirror)
			)
		)
		(property "Device Type" "TPAD28"
			(at 0.0127 -3.1877 0)
			(unlocked yes)
			(layer "B.Fab")
			(hide yes)
			(effects
				(font
					(size 1.016 1.016)
					(thickness 0.1524)
				)
				(justify mirror)
			)
		)
		(duplicate_pad_numbers_are_jumpers no)
		(fp_poly
			(pts
				(arc
					(start 0.3556 0)
					(mid -0.3556 0)
					(end 0.3556 0)
				)
			)
			(stroke
				(width 0)
				(type default)
			)
			(fill no)
			(layer "B.CrtYd")
		)
		(fp_poly
			(pts
				(arc
					(start 0.6096 0)
					(mid -0.6096 0)
					(end 0.6096 0)
				)
			)
			(stroke
				(width 0)
				(type default)
			)
			(fill no)
			(layer "B.Fab")
		)
		(pad "1" smd circle
			(at 0 0 180)
			(size 0.7112 0.7112)
			(layers "B.Cu" "B.Mask" "B.Paste")
			(net "TP_BMC_GPIOL5")
		)
	)
	(footprint ""
		(layer "B.Cu")
		(at 25.3238 -180.8988 -90)
		(property "Reference" "R483"
			(at 0 0 90)
			(layer "B.SilkS")
			(hide yes)
			(effects
				(font
					(size 1.27 1.27)
				)
				(justify mirror)
			)
		)
		(property "Value" "2D2R3J-2-GP"
			(at 0.0254 -2.5146 270)
			(unlocked yes)
			(layer "B.Fab")
			(hide yes)
			(effects
				(font
					(size 1.016 1.016)
					(thickness 0.1524)
				)
				(justify mirror)
			)
		)
		(property "Device Type" "R603H22"
			(at 0.0254 -4.0386 270)
			(unlocked yes)
			(layer "B.Fab")
			(hide yes)
			(effects
				(font
					(size 1.016 1.016)
					(thickness 0.1524)
				)
				(justify mirror)
			)
		)
		(duplicate_pad_numbers_are_jumpers no)
		(fp_line
			(start -0.2032 0)
			(end -0.4826 0)
			(stroke
				(width 0.2032)
				(type default)
			)
			(layer "B.SilkS")
		)
		(fp_line
			(start 0.4826 0)
			(end 0.2032 0)
			(stroke
				(width 0.2032)
				(type default)
			)
			(layer "B.SilkS")
		)
		(fp_rect
			(start 0.5842 1.3335)
			(end -0.5842 -1.3335)
			(stroke
				(width 0)
				(type default)
			)
			(fill no)
			(layer "B.CrtYd")
		)
		(fp_rect
			(start 0.5842 1.3335)
			(end -0.5842 -1.3335)
			(stroke
				(width 0)
				(type default)
			)
			(fill no)
			(layer "B.Fab")
		)
		(pad "1" smd custom
			(at 0 -0.762 90)
			(size 0.2159 0.2159)
			(layers "B.Cu" "B.Mask" "B.Paste")
			(net "P12V_STBY_VDD_PU2")
			(options
				(clearance outline)
				(anchor circle)
			)
			(primitives
				(gr_poly
					(pts
						(arc
							(start -0.3302 0.4318)
							(mid -0.402042 0.402042)
							(end -0.4318 0.3302)
						)
						(arc
							(start -0.4318 -0.3302)
							(mid -0.402042 -0.402042)
							(end -0.3302 -0.4318)
						)
						(arc
							(start 0.3302 -0.4318)
							(mid 0.402042 -0.402042)
							(end 0.4318 -0.3302)
						)
						(arc
							(start 0.4318 0.3302)
							(mid 0.402042 0.402042)
							(end 0.3302 0.4318)
						)
					)
					(width 0)
					(fill yes)
				)
			)
		)
		(pad "2" smd custom
			(at 0 0.762 90)
			(size 0.2159 0.2159)
			(layers "B.Cu" "B.Mask" "B.Paste")
			(net "P12V_STBY")
			(options
				(clearance outline)
				(anchor circle)
			)
			(primitives
				(gr_poly
					(pts
						(arc
							(start -0.3302 0.4318)
							(mid -0.402042 0.402042)
							(end -0.4318 0.3302)
						)
						(arc
							(start -0.4318 -0.3302)
							(mid -0.402042 -0.402042)
							(end -0.3302 -0.4318)
						)
						(arc
							(start 0.3302 -0.4318)
							(mid 0.402042 -0.402042)
							(end 0.4318 -0.3302)
						)
						(arc
							(start 0.4318 0.3302)
							(mid 0.402042 0.402042)
							(end 0.3302 0.4318)
						)
					)
					(width 0)
					(fill yes)
				)
			)
		)
	)
	(footprint ""
		(layer "B.Cu")
		(at 50.91557 -158.956756 -90)
		(property "Reference" "R400"
			(at 0 0 90)
			(layer "B.SilkS")
			(hide yes)
			(effects
				(font
					(size 1.27 1.27)
				)
				(justify mirror)
			)
		)
		(property "Value" "4K7R2F-GP"
			(at -0.064008 -3.993896 270)
			(unlocked yes)
			(layer "B.Fab")
			(hide yes)
			(effects
				(font
					(size 1.016 1.016)
					(thickness 0.1524)
				)
				(justify mirror)
			)
		)
		(property "Device Type" "R402H16"
			(at -0.064008 -5.517896 270)
			(unlocked yes)
			(layer "B.Fab")
			(hide yes)
			(effects
				(font
					(size 1.016 1.016)
					(thickness 0.1524)
				)
				(justify mirror)
			)
		)
		(duplicate_pad_numbers_are_jumpers no)
		(fp_line
			(start -0.508 -0.9398)
			(end 0.508 -0.9398)
			(stroke
				(width 0.1524)
				(type default)
			)
			(layer "B.SilkS")
		)
		(fp_line
			(start 0.508 -0.9398)
			(end 0.508 0.9398)
			(stroke
				(width 0.1524)
				(type default)
			)
			(layer "B.SilkS")
		)
		(fp_rect
			(start 0.508 0.9398)
			(end -0.508 -0.9398)
			(stroke
				(width 0)
				(type default)
			)
			(fill no)
			(layer "B.CrtYd")
		)
		(fp_rect
			(start 0.508 0.9398)
			(end -0.508 -0.9398)
			(stroke
				(width 0)
				(type default)
			)
			(fill no)
			(layer "B.Fab")
		)
		(pad "1" smd custom
			(at 0 -0.4445 90)
			(size 0.1397 0.1397)
			(layers "B.Cu" "B.Mask" "B.Paste")
			(net "GND")
			(options
				(clearance outline)
				(anchor circle)
			)
			(primitives
				(gr_poly
					(pts
						(arc
							(start -0.1778 0.2794)
							(mid -0.249642 0.249642)
							(end -0.2794 0.1778)
						)
						(arc
							(start -0.2794 -0.1778)
							(mid -0.249642 -0.249642)
							(end -0.1778 -0.2794)
						)
						(arc
							(start 0.1778 -0.2794)
							(mid 0.249642 -0.249642)
							(end 0.2794 -0.1778)
						)
						(arc
							(start 0.2794 0.1778)
							(mid 0.249642 0.249642)
							(end 0.1778 0.2794)
						)
					)
					(width 0)
					(fill yes)
				)
			)
		)
		(pad "2" smd custom
			(at 0 0.4445 90)
			(size 0.1397 0.1397)
			(layers "B.Cu" "B.Mask" "B.Paste")
			(net "UART_BMC_TX")
			(options
				(clearance outline)
				(anchor circle)
			)
			(primitives
				(gr_poly
					(pts
						(arc
							(start -0.1778 0.2794)
							(mid -0.249642 0.249642)
							(end -0.2794 0.1778)
						)
						(arc
							(start -0.2794 -0.1778)
							(mid -0.249642 -0.249642)
							(end -0.1778 -0.2794)
						)
						(arc
							(start 0.1778 -0.2794)
							(mid 0.249642 -0.249642)
							(end 0.2794 -0.1778)
						)
						(arc
							(start 0.2794 0.1778)
							(mid 0.249642 0.249642)
							(end 0.1778 0.2794)
						)
					)
					(width 0)
					(fill yes)
				)
			)
		)
	)
)
